# BASEBOARD_FAB2 (Tioga Pass) — schematic netlist excerpt (pin names and nets, part order shuffled) for the footprints in the layout excerpt that follows; sources: Cadence DE-HDL packaged netlist, KiCad conversion of Wiwynn_Tioga_Pass_MB.brd

C2T7  CAP  22UF 6.3V 20% X6S  pkg 0805  page 240 : A = P3V3_STBY ; B = GND
C2U21  CAP_A  0.1UF 16V 10% X7R  pkg 0402V  page 108 : A = P3V3 ; B = GND
C5G96  CAP_A  22.0UF 4V 20% X6S  pkg 0603V  page 243 : A = PVDDQ_GHJ ; B = GND

(kicad_pcb
	(version 20260206)
	(generator "pcbnew")
	(generator_version "10.0")
	(general
		(thickness 1.6)
		(legacy_teardrops no)
	)
	(paper "A4")
	(title_block
		(title "Wiwynn_Tioga_Pass_MB.brd")
		(comment 1 "Tioga Pass / footprints 3706-3708 of 4770")
	)
	(layers
		(0 "F.Cu" signal "TOP")
		(4 "In1.Cu" signal "L2GND")
		(6 "In2.Cu" signal "L3")
		(8 "In3.Cu" signal "L4GND")
		(10 "In4.Cu" signal "L5")
		(12 "In5.Cu" signal "L6GND")
		(14 "In6.Cu" signal "L7VCC")
		(16 "In7.Cu" signal "L8VCC")
		(18 "In8.Cu" signal "L9GND")
		(20 "In9.Cu" signal "L10")
		(22 "In10.Cu" signal "L11GND")
		(24 "In11.Cu" signal "L12")
		(26 "In12.Cu" signal "L13GND")
		(2 "B.Cu" signal "BOTTOM")
		(9 "F.Adhes" user "F.Adhesive")
		(11 "B.Adhes" user "B.Adhesive")
		(13 "F.Paste" user "Package Geometry/Pastemask Top")
		(15 "B.Paste" user "Package Geometry/Pastemask Bottom")
		(5 "F.SilkS" user "Ref Des/Silkscreen Top")
		(7 "B.SilkS" user "Ref Des/Silkscreen Bottom")
		(1 "F.Mask" user "Board Geometry/Soldermask Top")
		(3 "B.Mask" user "Board Geometry/Soldermask Bottom")
		(17 "Dwgs.User" user "User.Drawings")
		(19 "Cmts.User" user "User.Comments")
		(21 "Eco1.User" user "User.Eco1")
		(23 "Eco2.User" user "User.Eco2")
		(25 "Edge.Cuts" user "Board Geometry/Outline")
		(27 "Margin" user)
		(31 "F.CrtYd" user "Package Geometry/Place Bound Top")
		(29 "B.CrtYd" user "Package Geometry/Place Bound Bottom")
		(35 "F.Fab" user "Ref Des/Assembly Top")
		(33 "B.Fab" user "Ref Des/Assembly Bottom")
	)
	(footprint ""
		(layer "B.Cu")
		(at 111.000032 -12.954 90)
		(property "Reference" "C5G96"
			(at -1.14681 0.76708 180)
			(unlocked yes)
			(layer "B.SilkS")
			(effects
				(font
					(size 0.7874 0.5842)
					(thickness 0.1524)
				)
				(justify mirror)
			)
		)
		(property "Value" ""
			(at 0 0 90)
			(layer "B.Fab")
			(effects
				(font
					(size 1.27 1.27)
				)
				(justify mirror)
			)
		)
		(duplicate_pad_numbers_are_jumpers no)
		(fp_rect
			(start -0.4953 -0.2032)
			(end 0.4953 1.6002)
			(stroke
				(width 0)
				(type default)
			)
			(fill no)
			(layer "B.CrtYd")
		)
		(fp_line
			(start 0.4953 -0.2032)
			(end -0.4953 -0.2032)
			(stroke
				(width 0.1)
				(type default)
			)
			(layer "B.Fab")
		)
		(fp_line
			(start -0.4953 -0.2032)
			(end -0.4953 1.6002)
			(stroke
				(width 0.1)
				(type default)
			)
			(layer "B.Fab")
		)
		(fp_line
			(start 0.4953 1.6002)
			(end 0.4953 -0.2032)
			(stroke
				(width 0.1)
				(type default)
			)
			(layer "B.Fab")
		)
		(fp_line
			(start -0.4953 1.6002)
			(end 0.4953 1.6002)
			(stroke
				(width 0.1)
				(type default)
			)
			(layer "B.Fab")
		)
		(pad "1" smd rect
			(at 0 0 270)
			(size 0.762 0.889)
			(layers "B.Cu" "B.Mask" "B.Paste")
			(net "PVDDQ_GHJ")
		)
		(pad "2" smd rect
			(at 0 1.397 270)
			(size 0.762 0.889)
			(layers "B.Cu" "B.Mask" "B.Paste")
			(net "GND")
		)
		(zone
			(layer "B.Cu")
			(hatch none 0.5)
			(connect_pads
				(clearance 0)
			)
			(min_thickness 0.25)
			(keepout
				(tracks not_allowed)
				(vias allowed)
				(pads allowed)
				(copperpour not_allowed)
				(footprints allowed)
			)
			(placement
				(enabled no)
				(sheetname "")
			)
			(fill
				(thermal_gap 0.5)
				(thermal_bridge_width 0.5)
				(island_removal_mode 0)
			)
			(polygon
				(pts
					(xy 111.444532 -12.573) (xy 111.952532 -12.573) (xy 111.952532 -13.335) (xy 111.444532 -13.335)
				)
			)
		)
	)
	(footprint ""
		(layer "B.Cu")
		(at 465.641944 -7.48792 180)
		(property "Reference" "C2U21"
			(at 0 0 0)
			(layer "B.SilkS")
			(hide yes)
			(effects
				(font
					(size 1.27 1.27)
				)
				(justify mirror)
			)
		)
		(property "Value" ""
			(at 0 0 0)
			(layer "B.Fab")
			(effects
				(font
					(size 1.27 1.27)
				)
				(justify mirror)
			)
		)
		(duplicate_pad_numbers_are_jumpers no)
		(fp_poly
			(pts
				(xy -0.3048 -0.1016) (xy -0.3048 0.9906) (xy 0.3048 0.9906) (xy 0.3048 -0.1016)
			)
			(stroke
				(width 0)
				(type default)
			)
			(fill no)
			(layer "B.CrtYd")
		)
		(fp_line
			(start 0.3048 0.9906)
			(end -0.3048 0.9906)
			(stroke
				(width 0.1)
				(type default)
			)
			(layer "B.Fab")
		)
		(fp_line
			(start 0.3048 -0.1016)
			(end 0.3048 0.9906)
			(stroke
				(width 0.1)
				(type default)
			)
			(layer "B.Fab")
		)
		(fp_line
			(start -0.3048 0.9906)
			(end -0.3048 -0.1016)
			(stroke
				(width 0.1)
				(type default)
			)
			(layer "B.Fab")
		)
		(fp_line
			(start -0.3048 -0.1016)
			(end 0.3048 -0.1016)
			(stroke
				(width 0.1)
				(type default)
			)
			(layer "B.Fab")
		)
		(pad "1" smd rect
			(at 0 0)
			(size 0.508 0.508)
			(layers "B.Cu" "B.Mask" "B.Paste")
			(net "P3V3")
		)
		(pad "2" smd rect
			(at 0 0.889)
			(size 0.508 0.508)
			(layers "B.Cu" "B.Mask" "B.Paste")
			(net "GND")
		)
		(zone
			(layer "B.Cu")
			(hatch none 0.5)
			(connect_pads
				(clearance 0)
			)
			(min_thickness 0.25)
			(keepout
				(tracks not_allowed)
				(vias allowed)
				(pads allowed)
				(copperpour not_allowed)
				(footprints allowed)
			)
			(placement
				(enabled no)
				(sheetname "")
			)
			(fill
				(thermal_gap 0.5)
				(thermal_bridge_width 0.5)
				(island_removal_mode 0)
			)
			(polygon
				(pts
					(xy 465.387944 -8.12292) (xy 465.895944 -8.12292) (xy 465.895944 -7.74192) (xy 465.387944 -7.74192)
				)
			)
		)
		(zone
			(layer "B.Cu")
			(hatch none 0.5)
			(connect_pads
				(clearance 0)
			)
			(min_thickness 0.25)
			(keepout
				(tracks allowed)
				(vias not_allowed)
				(pads allowed)
				(copperpour not_allowed)
				(footprints allowed)
			)
			(placement
				(enabled no)
				(sheetname "")
			)
			(fill
				(thermal_gap 0.5)
				(thermal_bridge_width 0.5)
				(island_removal_mode 0)
			)
			(polygon
				(pts
					(xy 465.387944 -7.74192) (xy 465.895944 -7.74192) (xy 465.895944 -8.12292) (xy 465.387944 -8.12292)
				)
			)
		)
	)
	(footprint ""
		(layer "B.Cu")
		(at 464.82 -12.319 90)
		(property "Reference" "C2T7"
			(at 0 0 90)
			(layer "B.SilkS")
			(hide yes)
			(effects
				(font
					(size 1.27 1.27)
				)
				(justify mirror)
			)
		)
		(property "Value" ""
			(at 0 0 90)
			(layer "B.Fab")
			(effects
				(font
					(size 1.27 1.27)
				)
				(justify mirror)
			)
		)
		(duplicate_pad_numbers_are_jumpers no)
		(fp_rect
			(start 0.7239 -0.2159)
			(end -0.7239 1.9939)
			(stroke
				(width 0)
				(type default)
			)
			(fill no)
			(layer "B.CrtYd")
		)
		(fp_line
			(start 0.7239 -0.2159)
			(end 0.7239 1.9939)
			(stroke
				(width 0.1)
				(type default)
			)
			(layer "B.Fab")
		)
		(fp_line
			(start -0.7239 -0.2159)
			(end 0.7239 -0.2159)
			(stroke
				(width 0.1)
				(type default)
			)
			(layer "B.Fab")
		)
		(fp_line
			(start 0.7239 1.9939)
			(end -0.7239 1.9939)
			(stroke
				(width 0.1)
				(type default)
			)
			(layer "B.Fab")
		)
		(fp_line
			(start -0.7239 1.9939)
			(end -0.7239 -0.2159)
			(stroke
				(width 0.1)
				(type default)
			)
			(layer "B.Fab")
		)
		(pad "1" smd rect
			(at 0 0 270)
			(size 1.27 1.016)
			(layers "B.Cu" "B.Mask" "B.Paste")
			(net "P3V3_STBY")
		)
		(pad "2" smd rect
			(at 0 1.778 270)
			(size 1.27 1.016)
			(layers "B.Cu" "B.Mask" "B.Paste")
			(net "GND")
		)
		(zone
			(layer "B.Cu")
			(hatch none 0.5)
			(connect_pads
				(clearance 0)
			)
			(min_thickness 0.25)
			(keepout
				(tracks not_allowed)
				(vias allowed)
				(pads allowed)
				(copperpour not_allowed)
				(footprints allowed)
			)
			(placement
				(enabled no)
				(sheetname "")
			)
			(fill
				(thermal_gap 0.5)
				(thermal_bridge_width 0.5)
				(island_removal_mode 0)
			)
			(polygon
				(pts
					(xy 465.328 -12.954) (xy 465.328 -11.684) (xy 466.09 -11.684) (xy 466.09 -12.954)
				)
			)
		)
	)
)
